# S9S_MB_2U (Grand Teton) — schematic netlist excerpt (pin names and nets, part order shuffled) for the footprints in the layout excerpt that follows; sources: Cadence DE-HDL packaged netlist, KiCad conversion of 03242023_DA0F0TMBIJ0_F0T_Motherboard_J_brd_V01_OCP.brd

PC587  Q_CAPP  330UF 2.5V +10/-35% EMPTY  pkg SMLF  page 285 : A = PVCCIN_CPU1 ; B = GND
PR1300  Q_RES  2.2 1% CHIP  pkg 0402LF  page 272 : A = PVCCFA_EHV_FIVRA_CPU0_PVCC2 ; B = PVCCFA_EHV_FIVRA_CPU0_VDD4

(kicad_pcb
	(version 20260206)
	(generator "pcbnew")
	(generator_version "10.0")
	(general
		(thickness 1.6)
		(legacy_teardrops no)
	)
	(paper "A4")
	(title_block
		(title "03242023_DA0F0TMBIJ0_F0T_Motherboard_J_brd_V01_OCP.brd")
		(comment 1 "Grand Teton / footprints 4271-4272 of 6105")
	)
	(layers
		(0 "F.Cu" signal "TOP")
		(4 "In1.Cu" signal "GND")
		(6 "In2.Cu" signal "IN1")
		(8 "In3.Cu" signal "GND1")
		(10 "In4.Cu" signal "IN2")
		(12 "In5.Cu" signal "GND2")
		(14 "In6.Cu" signal "IN3")
		(16 "In7.Cu" signal "GND3")
		(18 "In8.Cu" signal "VCC")
		(20 "In9.Cu" signal "VCC1")
		(22 "In10.Cu" signal "GND4")
		(24 "In11.Cu" signal "IN4")
		(26 "In12.Cu" signal "GND5")
		(28 "In13.Cu" signal "IN5")
		(30 "In14.Cu" signal "GND6")
		(32 "In15.Cu" signal "IN6")
		(34 "In16.Cu" signal "GND7")
		(2 "B.Cu" signal "BOTTOM")
		(9 "F.Adhes" user "F.Adhesive")
		(11 "B.Adhes" user "B.Adhesive")
		(13 "F.Paste" user "Package Geometry/Pastemask Top")
		(15 "B.Paste" user "Package Geometry/Pastemask Bottom")
		(5 "F.SilkS" user "Ref Des/Silkscreen Top")
		(7 "B.SilkS" user "Ref Des/Silkscreen Bottom")
		(1 "F.Mask" user "Board Geometry/Soldermask Top")
		(3 "B.Mask" user "Board Geometry/Soldermask Bottom")
		(17 "Dwgs.User" user "User.Drawings")
		(19 "Cmts.User" user "User.Comments")
		(21 "Eco1.User" user "User.Eco1")
		(23 "Eco2.User" user "User.Eco2")
		(25 "Edge.Cuts" user "Board Geometry/Outline")
		(27 "Margin" user)
		(31 "F.CrtYd" user "Package Geometry/Place Bound Top")
		(29 "B.CrtYd" user "Package Geometry/Place Bound Bottom")
		(35 "F.Fab" user "Ref Des/Assembly Top")
		(33 "B.Fab" user "Ref Des/Assembly Bottom")
	)
	(footprint ""
		(layer "B.Cu")
		(at 129.545588 -329.921616 -90)
		(property "Reference" "PC587"
			(at 0 0 90)
			(layer "B.SilkS")
			(hide yes)
			(effects
				(font
					(size 1.27 1.27)
				)
				(justify mirror)
			)
		)
		(property "Value" ""
			(at 0 0 90)
			(layer "B.Fab")
			(effects
				(font
					(size 1.27 1.27)
				)
				(justify mirror)
			)
		)
		(duplicate_pad_numbers_are_jumpers no)
		(fp_line
			(start -4.533392 2.249932)
			(end 4.533392 2.249932)
			(stroke
				(width 0.1524)
				(type default)
			)
			(layer "B.SilkS")
		)
		(fp_line
			(start 4.533392 2.249932)
			(end 4.533392 -2.249932)
			(stroke
				(width 0.1524)
				(type default)
			)
			(layer "B.SilkS")
		)
		(fp_line
			(start -4.533392 -2.249932)
			(end -4.533392 2.249932)
			(stroke
				(width 0.1524)
				(type default)
			)
			(layer "B.SilkS")
		)
		(fp_line
			(start 4.533392 -2.249932)
			(end -4.533392 -2.249932)
			(stroke
				(width 0.1524)
				(type default)
			)
			(layer "B.SilkS")
		)
		(fp_rect
			(start 5.39242 2.326132)
			(end 4.533392 -2.326132)
			(stroke
				(width 0)
				(type default)
			)
			(fill yes)
			(layer "B.SilkS")
		)
		(fp_line
			(start -3.750056 2.249932)
			(end 3.750056 2.249932)
			(stroke
				(width 0.1)
				(type default)
			)
			(layer "B.Fab")
		)
		(fp_line
			(start 3.750056 2.249932)
			(end 3.750056 -2.249932)
			(stroke
				(width 0.1)
				(type default)
			)
			(layer "B.Fab")
		)
		(fp_line
			(start -3.750056 -2.249932)
			(end -3.750056 2.249932)
			(stroke
				(width 0.1)
				(type default)
			)
			(layer "B.Fab")
		)
		(fp_line
			(start 3.750056 -2.249932)
			(end -3.750056 -2.249932)
			(stroke
				(width 0.1)
				(type default)
			)
			(layer "B.Fab")
		)
		(fp_text user "-"
			(at -4.507992 1.355598 270)
			(unlocked yes)
			(layer "B.SilkS")
			(effects
				(font
					(size 1.905 1.4224)
					(thickness 0.1524)
				)
				(justify left mirror)
			)
		)
		(fp_text user "+"
			(at 6.322314 0.786384 180)
			(unlocked yes)
			(layer "B.SilkS")
			(effects
				(font
					(size 1.905 1.4224)
					(thickness 0.1524)
				)
				(justify left mirror)
			)
		)
		(fp_text user "+"
			(at 6.322314 0.786384 180)
			(unlocked yes)
			(layer "B.Fab")
			(effects
				(font
					(size 1.905 1.4224)
					(thickness 0.1524)
				)
				(justify left mirror)
			)
		)
		(fp_text user "-"
			(at -4.8514 -0.14605 270)
			(unlocked yes)
			(layer "B.Fab")
			(effects
				(font
					(size 1.905 1.4224)
					(thickness 0.1524)
				)
				(justify left mirror)
			)
		)
		(pad "1" smd rect
			(at 3.199892 0 90)
			(size 2.413 2.8194)
			(layers "B.Cu" "B.Mask" "B.Paste")
			(net "PVCCIN_CPU1")
		)
		(pad "2" smd rect
			(at -3.199892 0 90)
			(size 2.413 2.8194)
			(layers "B.Cu" "B.Mask" "B.Paste")
			(net "GND")
		)
	)
	(footprint ""
		(layer "B.Cu")
		(at 286.2834 -363.79277 -90)
		(property "Reference" "PR1300"
			(at 0 0 90)
			(layer "B.SilkS")
			(hide yes)
			(effects
				(font
					(size 1.27 1.27)
				)
				(justify mirror)
			)
		)
		(property "Value" ""
			(at 0 0 90)
			(layer "B.Fab")
			(effects
				(font
					(size 1.27 1.27)
				)
				(justify mirror)
			)
		)
		(duplicate_pad_numbers_are_jumpers no)
		(fp_line
			(start -0.7874 0.4064)
			(end 0.7874 0.4064)
			(stroke
				(width 0.1524)
				(type default)
			)
			(layer "B.SilkS")
		)
		(fp_line
			(start 0.7874 0.4064)
			(end 0.7874 -0.4064)
			(stroke
				(width 0.1524)
				(type default)
			)
			(layer "B.SilkS")
		)
		(fp_line
			(start -0.7874 -0.4064)
			(end -0.7874 0.4064)
			(stroke
				(width 0.1524)
				(type default)
			)
			(layer "B.SilkS")
		)
		(fp_line
			(start 0.7874 -0.4064)
			(end -0.7874 -0.4064)
			(stroke
				(width 0.1524)
				(type default)
			)
			(layer "B.SilkS")
		)
		(fp_line
			(start -0.67945 0.3048)
			(end -0.120396 0.3048)
			(stroke
				(width 0.1)
				(type default)
			)
			(layer "B.Fab")
		)
		(fp_line
			(start -0.120396 0.3048)
			(end -0.120396 0.2794)
			(stroke
				(width 0.1)
				(type default)
			)
			(layer "B.Fab")
		)
		(fp_line
			(start 0.12065 0.3048)
			(end 0.67945 0.3048)
			(stroke
				(width 0.1)
				(type default)
			)
			(layer "B.Fab")
		)
		(fp_line
			(start 0.67945 0.3048)
			(end 0.67945 -0.305054)
			(stroke
				(width 0.1)
				(type default)
			)
			(layer "B.Fab")
		)
		(fp_line
			(start -0.120396 0.2794)
			(end 0.12065 0.2794)
			(stroke
				(width 0.1)
				(type default)
			)
			(layer "B.Fab")
		)
		(fp_line
			(start 0.12065 0.2794)
			(end 0.12065 0.3048)
			(stroke
				(width 0.1)
				(type default)
			)
			(layer "B.Fab")
		)
		(fp_line
			(start -0.12065 -0.2794)
			(end -0.12065 -0.3048)
			(stroke
				(width 0.1)
				(type default)
			)
			(layer "B.Fab")
		)
		(fp_line
			(start 0.12065 -0.2794)
			(end -0.12065 -0.2794)
			(stroke
				(width 0.1)
				(type default)
			)
			(layer "B.Fab")
		)
		(fp_line
			(start -0.67945 -0.3048)
			(end -0.67945 0.3048)
			(stroke
				(width 0.1)
				(type default)
			)
			(layer "B.Fab")
		)
		(fp_line
			(start -0.12065 -0.3048)
			(end -0.67945 -0.3048)
			(stroke
				(width 0.1)
				(type default)
			)
			(layer "B.Fab")
		)
		(fp_line
			(start 0.12065 -0.305054)
			(end 0.12065 -0.2794)
			(stroke
				(width 0.1)
				(type default)
			)
			(layer "B.Fab")
		)
		(fp_line
			(start 0.67945 -0.305054)
			(end 0.12065 -0.305054)
			(stroke
				(width 0.1)
				(type default)
			)
			(layer "B.Fab")
		)
		(pad "1" smd circle
			(at 0.40005 0 90)
			(size 0 0)
			(layers "B.Cu" "B.Mask" "B.Paste")
			(net "PVCCFA_EHV_FIVRA_CPU0_PVCC2")
		)
		(pad "2" smd circle
			(at -0.40005 0 90)
			(size 0 0)
			(layers "B.Cu" "B.Mask" "B.Paste")
			(net "PVCCFA_EHV_FIVRA_CPU0_VDD4")
		)
	)
)
